# T6G (Grand Teton) — schematic netlist excerpt (pin names and nets, part order shuffled) for the footprints in the layout excerpt that follows; sources: Cadence DE-HDL packaged netlist, KiCad conversion of 04192023_DAF0TMB3IC0_F0TG_MB_C_brd_V02_OCP.brd

R1078  Q_RES  4.7K 5% CHIP  pkg 0201LF  page 298 : A = TEST2_RT_CPU0_P2 ; B = GND
C197  Q_CAP  1000PF 50V 5% X7R  pkg 0402  page 207 : A = PVDD11_S3_P0_EN_R ; B = GND
R6781  Q_RES  0 5% CHIP  pkg 0402LF  page 81 : A = RST_SMB_RT_ROM_R2_N ; B = RST_SMB_RT_ROM_R1_N

(kicad_pcb
	(version 20260206)
	(generator "pcbnew")
	(generator_version "10.0")
	(general
		(thickness 1.6)
		(legacy_teardrops no)
	)
	(paper "A4")
	(title_block
		(title "04192023_DAF0TMB3IC0_F0TG_MB_C_brd_V02_OCP.brd")
		(comment 1 "Grand Teton / footprints 4467-4469 of 8354")
	)
	(layers
		(0 "F.Cu" signal "TOP")
		(4 "In1.Cu" signal "GND")
		(6 "In2.Cu" signal "IN1")
		(8 "In3.Cu" signal "GND1")
		(10 "In4.Cu" signal "IN2")
		(12 "In5.Cu" signal "GND2")
		(14 "In6.Cu" signal "IN3")
		(16 "In7.Cu" signal "GND3")
		(18 "In8.Cu" signal "VCC")
		(20 "In9.Cu" signal "VCC1")
		(22 "In10.Cu" signal "GND4")
		(24 "In11.Cu" signal "IN4")
		(26 "In12.Cu" signal "GND5")
		(28 "In13.Cu" signal "IN5")
		(30 "In14.Cu" signal "GND6")
		(32 "In15.Cu" signal "IN6")
		(34 "In16.Cu" signal "GND7")
		(2 "B.Cu" signal "BOTTOM")
		(9 "F.Adhes" user "F.Adhesive")
		(11 "B.Adhes" user "B.Adhesive")
		(13 "F.Paste" user "Package Geometry/Pastemask Top")
		(15 "B.Paste" user "Package Geometry/Pastemask Bottom")
		(5 "F.SilkS" user "Ref Des/Silkscreen Top")
		(7 "B.SilkS" user "Ref Des/Silkscreen Bottom")
		(1 "F.Mask" user "Board Geometry/Soldermask Top")
		(3 "B.Mask" user "Board Geometry/Soldermask Bottom")
		(17 "Dwgs.User" user "User.Drawings")
		(19 "Cmts.User" user "User.Comments")
		(21 "Eco1.User" user "User.Eco1")
		(23 "Eco2.User" user "User.Eco2")
		(25 "Edge.Cuts" user "Board Geometry/Outline")
		(27 "Margin" user)
		(31 "F.CrtYd" user "Package Geometry/Place Bound Top")
		(29 "B.CrtYd" user "Package Geometry/Place Bound Bottom")
		(35 "F.Fab" user "Ref Des/Assembly Top")
		(33 "B.Fab" user "Ref Des/Assembly Bottom")
	)
	(footprint ""
		(layer "F.Cu")
		(at 414.331912 -363.790992 180)
		(property "Reference" "C197"
			(at 0 0 180)
			(layer "F.SilkS")
			(hide yes)
			(effects
				(font
					(size 1.27 1.27)
				)
			)
		)
		(property "Value" ""
			(at 0 0 180)
			(layer "F.Fab")
			(effects
				(font
					(size 1.27 1.27)
				)
			)
		)
		(duplicate_pad_numbers_are_jumpers no)
		(fp_line
			(start 0.7874 0.4064)
			(end -0.7874 0.4064)
			(stroke
				(width 0.1524)
				(type default)
			)
			(layer "F.SilkS")
		)
		(fp_line
			(start 0.7874 -0.4064)
			(end 0.7874 0.4064)
			(stroke
				(width 0.1524)
				(type default)
			)
			(layer "F.SilkS")
		)
		(fp_line
			(start -0.7874 0.4064)
			(end -0.7874 -0.4064)
			(stroke
				(width 0.1524)
				(type default)
			)
			(layer "F.SilkS")
		)
		(fp_line
			(start -0.7874 -0.4064)
			(end 0.7874 -0.4064)
			(stroke
				(width 0.1524)
				(type default)
			)
			(layer "F.SilkS")
		)
		(fp_line
			(start 0.67945 0.3048)
			(end 0.120396 0.3048)
			(stroke
				(width 0.1)
				(type default)
			)
			(layer "F.Fab")
		)
		(fp_line
			(start 0.67945 -0.3048)
			(end 0.67945 0.3048)
			(stroke
				(width 0.1)
				(type default)
			)
			(layer "F.Fab")
		)
		(fp_line
			(start 0.12065 -0.2794)
			(end 0.12065 -0.3048)
			(stroke
				(width 0.1)
				(type default)
			)
			(layer "F.Fab")
		)
		(fp_line
			(start 0.12065 -0.3048)
			(end 0.67945 -0.3048)
			(stroke
				(width 0.1)
				(type default)
			)
			(layer "F.Fab")
		)
		(fp_line
			(start 0.120396 0.3048)
			(end 0.120396 0.2794)
			(stroke
				(width 0.1)
				(type default)
			)
			(layer "F.Fab")
		)
		(fp_line
			(start 0.120396 0.2794)
			(end -0.12065 0.2794)
			(stroke
				(width 0.1)
				(type default)
			)
			(layer "F.Fab")
		)
		(fp_line
			(start -0.12065 0.3048)
			(end -0.67945 0.3048)
			(stroke
				(width 0.1)
				(type default)
			)
			(layer "F.Fab")
		)
		(fp_line
			(start -0.12065 0.2794)
			(end -0.12065 0.3048)
			(stroke
				(width 0.1)
				(type default)
			)
			(layer "F.Fab")
		)
		(fp_line
			(start -0.12065 -0.2794)
			(end 0.12065 -0.2794)
			(stroke
				(width 0.1)
				(type default)
			)
			(layer "F.Fab")
		)
		(fp_line
			(start -0.12065 -0.305054)
			(end -0.12065 -0.2794)
			(stroke
				(width 0.1)
				(type default)
			)
			(layer "F.Fab")
		)
		(fp_line
			(start -0.67945 0.3048)
			(end -0.67945 -0.305054)
			(stroke
				(width 0.1)
				(type default)
			)
			(layer "F.Fab")
		)
		(fp_line
			(start -0.67945 -0.305054)
			(end -0.12065 -0.305054)
			(stroke
				(width 0.1)
				(type default)
			)
			(layer "F.Fab")
		)
		(pad "1" smd circle
			(at -0.40005 0 180)
			(size 0 0)
			(layers "F.Cu" "F.Mask" "F.Paste")
			(net "PVDD11_S3_P0_EN_R")
		)
		(pad "2" smd circle
			(at 0.40005 0 180)
			(size 0 0)
			(layers "F.Cu" "F.Mask" "F.Paste")
			(net "GND")
		)
	)
	(footprint ""
		(layer "F.Cu")
		(at 217.066114 -126.710694)
		(property "Reference" "R6781"
			(at 0 0 0)
			(layer "F.SilkS")
			(hide yes)
			(effects
				(font
					(size 1.27 1.27)
				)
			)
		)
		(property "Value" ""
			(at 0 0 0)
			(layer "F.Fab")
			(effects
				(font
					(size 1.27 1.27)
				)
			)
		)
		(duplicate_pad_numbers_are_jumpers no)
		(fp_line
			(start -0.7874 -0.4064)
			(end 0.7874 -0.4064)
			(stroke
				(width 0.1524)
				(type default)
			)
			(layer "F.SilkS")
		)
		(fp_line
			(start -0.7874 0.4064)
			(end -0.7874 -0.4064)
			(stroke
				(width 0.1524)
				(type default)
			)
			(layer "F.SilkS")
		)
		(fp_line
			(start 0.7874 -0.4064)
			(end 0.7874 0.4064)
			(stroke
				(width 0.1524)
				(type default)
			)
			(layer "F.SilkS")
		)
		(fp_line
			(start 0.7874 0.4064)
			(end -0.7874 0.4064)
			(stroke
				(width 0.1524)
				(type default)
			)
			(layer "F.SilkS")
		)
		(fp_line
			(start -0.67945 -0.305054)
			(end -0.12065 -0.305054)
			(stroke
				(width 0.1)
				(type default)
			)
			(layer "F.Fab")
		)
		(fp_line
			(start -0.67945 0.3048)
			(end -0.67945 -0.305054)
			(stroke
				(width 0.1)
				(type default)
			)
			(layer "F.Fab")
		)
		(fp_line
			(start -0.12065 -0.305054)
			(end -0.12065 -0.2794)
			(stroke
				(width 0.1)
				(type default)
			)
			(layer "F.Fab")
		)
		(fp_line
			(start -0.12065 -0.2794)
			(end 0.12065 -0.2794)
			(stroke
				(width 0.1)
				(type default)
			)
			(layer "F.Fab")
		)
		(fp_line
			(start -0.12065 0.2794)
			(end -0.12065 0.3048)
			(stroke
				(width 0.1)
				(type default)
			)
			(layer "F.Fab")
		)
		(fp_line
			(start -0.12065 0.3048)
			(end -0.67945 0.3048)
			(stroke
				(width 0.1)
				(type default)
			)
			(layer "F.Fab")
		)
		(fp_line
			(start 0.120396 0.2794)
			(end -0.12065 0.2794)
			(stroke
				(width 0.1)
				(type default)
			)
			(layer "F.Fab")
		)
		(fp_line
			(start 0.120396 0.3048)
			(end 0.120396 0.2794)
			(stroke
				(width 0.1)
				(type default)
			)
			(layer "F.Fab")
		)
		(fp_line
			(start 0.12065 -0.3048)
			(end 0.67945 -0.3048)
			(stroke
				(width 0.1)
				(type default)
			)
			(layer "F.Fab")
		)
		(fp_line
			(start 0.12065 -0.2794)
			(end 0.12065 -0.3048)
			(stroke
				(width 0.1)
				(type default)
			)
			(layer "F.Fab")
		)
		(fp_line
			(start 0.67945 -0.3048)
			(end 0.67945 0.3048)
			(stroke
				(width 0.1)
				(type default)
			)
			(layer "F.Fab")
		)
		(fp_line
			(start 0.67945 0.3048)
			(end 0.120396 0.3048)
			(stroke
				(width 0.1)
				(type default)
			)
			(layer "F.Fab")
		)
		(pad "1" smd circle
			(at -0.40005 0)
			(size 0 0)
			(layers "F.Cu" "F.Mask" "F.Paste")
			(net "RST_SMB_RT_ROM_R2_N")
		)
		(pad "2" smd circle
			(at 0.40005 0)
			(size 0 0)
			(layers "F.Cu" "F.Mask" "F.Paste")
			(net "RST_SMB_RT_ROM_R1_N")
		)
	)
	(footprint ""
		(layer "F.Cu")
		(at 398.893538 -392.1252)
		(property "Reference" "R1078"
			(at 0 0 0)
			(layer "F.SilkS")
			(hide yes)
			(effects
				(font
					(size 1.27 1.27)
				)
			)
		)
		(property "Value" ""
			(at 0 0 0)
			(layer "F.Fab")
			(effects
				(font
					(size 1.27 1.27)
				)
			)
		)
		(duplicate_pad_numbers_are_jumpers no)
		(fp_line
			(start -0.32512 -0.175006)
			(end 0.32512 -0.175006)
			(stroke
				(width 0.1)
				(type default)
			)
			(layer "F.Fab")
		)
		(fp_line
			(start -0.32512 0.175006)
			(end -0.32512 -0.175006)
			(stroke
				(width 0.1)
				(type default)
			)
			(layer "F.Fab")
		)
		(fp_line
			(start 0.32512 -0.175006)
			(end 0.32512 0.175006)
			(stroke
				(width 0.1)
				(type default)
			)
			(layer "F.Fab")
		)
		(fp_line
			(start 0.32512 0.175006)
			(end -0.32512 0.175006)
			(stroke
				(width 0.1)
				(type default)
			)
			(layer "F.Fab")
		)
		(pad "1" smd rect
			(at -0.2667 0)
			(size 0.3048 0.381)
			(layers "F.Cu" "F.Mask" "F.Paste")
			(net "TEST2_RT_CPU0_P2")
		)
		(pad "2" smd rect
			(at 0.2667 0 180)
			(size 0.3048 0.381)
			(layers "F.Cu" "F.Mask" "F.Paste")
			(net "GND")
		)
	)
)
